# T6G (Grand Teton) — schematic netlist excerpt (pin names and nets, part order shuffled) for the footprints in the layout excerpt that follows; sources: Cadence DE-HDL packaged netlist, KiCad conversion of 04192023_DAF0TMB3IC0_F0TG_MB_C_brd_V02_OCP.brd

R3797  Q_RES  100K 1% CHIP  pkg 0402LF  page 134 : A = P3V3_AUX ; B = HP_LVC3_OCP_V3_1_P12V_PWRGD
R1622  Q_RES  4.7K 5% CHIP  pkg 0402LF  page 172 : A = P3V3_AUX ; B = JTAG_BMC_OE_N

(kicad_pcb
	(version 20260206)
	(generator "pcbnew")
	(generator_version "10.0")
	(general
		(thickness 1.6)
		(legacy_teardrops no)
	)
	(paper "A4")
	(title_block
		(title "04192023_DAF0TMB3IC0_F0TG_MB_C_brd_V02_OCP.brd")
		(comment 1 "Grand Teton / footprints 2184-2185 of 8354")
	)
	(layers
		(0 "F.Cu" signal "TOP")
		(4 "In1.Cu" signal "GND")
		(6 "In2.Cu" signal "IN1")
		(8 "In3.Cu" signal "GND1")
		(10 "In4.Cu" signal "IN2")
		(12 "In5.Cu" signal "GND2")
		(14 "In6.Cu" signal "IN3")
		(16 "In7.Cu" signal "GND3")
		(18 "In8.Cu" signal "VCC")
		(20 "In9.Cu" signal "VCC1")
		(22 "In10.Cu" signal "GND4")
		(24 "In11.Cu" signal "IN4")
		(26 "In12.Cu" signal "GND5")
		(28 "In13.Cu" signal "IN5")
		(30 "In14.Cu" signal "GND6")
		(32 "In15.Cu" signal "IN6")
		(34 "In16.Cu" signal "GND7")
		(2 "B.Cu" signal "BOTTOM")
		(9 "F.Adhes" user "F.Adhesive")
		(11 "B.Adhes" user "B.Adhesive")
		(13 "F.Paste" user "Package Geometry/Pastemask Top")
		(15 "B.Paste" user "Package Geometry/Pastemask Bottom")
		(5 "F.SilkS" user "Ref Des/Silkscreen Top")
		(7 "B.SilkS" user "Ref Des/Silkscreen Bottom")
		(1 "F.Mask" user "Board Geometry/Soldermask Top")
		(3 "B.Mask" user "Board Geometry/Soldermask Bottom")
		(17 "Dwgs.User" user "User.Drawings")
		(19 "Cmts.User" user "User.Comments")
		(21 "Eco1.User" user "User.Eco1")
		(23 "Eco2.User" user "User.Eco2")
		(25 "Edge.Cuts" user "Board Geometry/Outline")
		(27 "Margin" user)
		(31 "F.CrtYd" user "Package Geometry/Place Bound Top")
		(29 "B.CrtYd" user "Package Geometry/Place Bound Bottom")
		(35 "F.Fab" user "Ref Des/Assembly Top")
		(33 "B.Fab" user "Ref Des/Assembly Bottom")
	)
	(footprint ""
		(layer "F.Cu")
		(at 454.847452 -19.427698 -90)
		(property "Reference" "R3797"
			(at 0 0 270)
			(layer "F.SilkS")
			(hide yes)
			(effects
				(font
					(size 1.27 1.27)
				)
			)
		)
		(property "Value" ""
			(at 0 0 270)
			(layer "F.Fab")
			(effects
				(font
					(size 1.27 1.27)
				)
			)
		)
		(duplicate_pad_numbers_are_jumpers no)
		(fp_line
			(start -0.7874 0.4064)
			(end -0.7874 -0.4064)
			(stroke
				(width 0.1524)
				(type default)
			)
			(layer "F.SilkS")
		)
		(fp_line
			(start 0.7874 0.4064)
			(end -0.7874 0.4064)
			(stroke
				(width 0.1524)
				(type default)
			)
			(layer "F.SilkS")
		)
		(fp_line
			(start -0.7874 -0.4064)
			(end 0.7874 -0.4064)
			(stroke
				(width 0.1524)
				(type default)
			)
			(layer "F.SilkS")
		)
		(fp_line
			(start 0.7874 -0.4064)
			(end 0.7874 0.4064)
			(stroke
				(width 0.1524)
				(type default)
			)
			(layer "F.SilkS")
		)
		(fp_line
			(start -0.67945 0.3048)
			(end -0.67945 -0.305054)
			(stroke
				(width 0.1)
				(type default)
			)
			(layer "F.Fab")
		)
		(fp_line
			(start -0.12065 0.3048)
			(end -0.67945 0.3048)
			(stroke
				(width 0.1)
				(type default)
			)
			(layer "F.Fab")
		)
		(fp_line
			(start 0.120396 0.3048)
			(end 0.120396 0.2794)
			(stroke
				(width 0.1)
				(type default)
			)
			(layer "F.Fab")
		)
		(fp_line
			(start 0.67945 0.3048)
			(end 0.120396 0.3048)
			(stroke
				(width 0.1)
				(type default)
			)
			(layer "F.Fab")
		)
		(fp_line
			(start -0.12065 0.2794)
			(end -0.12065 0.3048)
			(stroke
				(width 0.1)
				(type default)
			)
			(layer "F.Fab")
		)
		(fp_line
			(start 0.120396 0.2794)
			(end -0.12065 0.2794)
			(stroke
				(width 0.1)
				(type default)
			)
			(layer "F.Fab")
		)
		(fp_line
			(start -0.12065 -0.2794)
			(end 0.12065 -0.2794)
			(stroke
				(width 0.1)
				(type default)
			)
			(layer "F.Fab")
		)
		(fp_line
			(start 0.12065 -0.2794)
			(end 0.12065 -0.3048)
			(stroke
				(width 0.1)
				(type default)
			)
			(layer "F.Fab")
		)
		(fp_line
			(start 0.12065 -0.3048)
			(end 0.67945 -0.3048)
			(stroke
				(width 0.1)
				(type default)
			)
			(layer "F.Fab")
		)
		(fp_line
			(start 0.67945 -0.3048)
			(end 0.67945 0.3048)
			(stroke
				(width 0.1)
				(type default)
			)
			(layer "F.Fab")
		)
		(fp_line
			(start -0.67945 -0.305054)
			(end -0.12065 -0.305054)
			(stroke
				(width 0.1)
				(type default)
			)
			(layer "F.Fab")
		)
		(fp_line
			(start -0.12065 -0.305054)
			(end -0.12065 -0.2794)
			(stroke
				(width 0.1)
				(type default)
			)
			(layer "F.Fab")
		)
		(pad "1" smd circle
			(at -0.40005 0 270)
			(size 0 0)
			(layers "F.Cu" "F.Mask" "F.Paste")
			(net "P3V3_AUX")
		)
		(pad "2" smd circle
			(at 0.40005 0 270)
			(size 0 0)
			(layers "F.Cu" "F.Mask" "F.Paste")
			(net "HP_LVC3_OCP_V3_1_P12V_PWRGD")
		)
	)
	(footprint ""
		(layer "F.Cu")
		(at 145.474944 -59.898534)
		(property "Reference" "R1622"
			(at 0 0 0)
			(layer "F.SilkS")
			(hide yes)
			(effects
				(font
					(size 1.27 1.27)
				)
			)
		)
		(property "Value" ""
			(at 0 0 0)
			(layer "F.Fab")
			(effects
				(font
					(size 1.27 1.27)
				)
			)
		)
		(duplicate_pad_numbers_are_jumpers no)
		(fp_line
			(start -0.7874 -0.4064)
			(end 0.7874 -0.4064)
			(stroke
				(width 0.1524)
				(type default)
			)
			(layer "F.SilkS")
		)
		(fp_line
			(start -0.7874 0.4064)
			(end -0.7874 -0.4064)
			(stroke
				(width 0.1524)
				(type default)
			)
			(layer "F.SilkS")
		)
		(fp_line
			(start 0.7874 -0.4064)
			(end 0.7874 0.4064)
			(stroke
				(width 0.1524)
				(type default)
			)
			(layer "F.SilkS")
		)
		(fp_line
			(start 0.7874 0.4064)
			(end -0.7874 0.4064)
			(stroke
				(width 0.1524)
				(type default)
			)
			(layer "F.SilkS")
		)
		(fp_line
			(start -0.67945 -0.305054)
			(end -0.12065 -0.305054)
			(stroke
				(width 0.1)
				(type default)
			)
			(layer "F.Fab")
		)
		(fp_line
			(start -0.67945 0.3048)
			(end -0.67945 -0.305054)
			(stroke
				(width 0.1)
				(type default)
			)
			(layer "F.Fab")
		)
		(fp_line
			(start -0.12065 -0.305054)
			(end -0.12065 -0.2794)
			(stroke
				(width 0.1)
				(type default)
			)
			(layer "F.Fab")
		)
		(fp_line
			(start -0.12065 -0.2794)
			(end 0.12065 -0.2794)
			(stroke
				(width 0.1)
				(type default)
			)
			(layer "F.Fab")
		)
		(fp_line
			(start -0.12065 0.2794)
			(end -0.12065 0.3048)
			(stroke
				(width 0.1)
				(type default)
			)
			(layer "F.Fab")
		)
		(fp_line
			(start -0.12065 0.3048)
			(end -0.67945 0.3048)
			(stroke
				(width 0.1)
				(type default)
			)
			(layer "F.Fab")
		)
		(fp_line
			(start 0.120396 0.2794)
			(end -0.12065 0.2794)
			(stroke
				(width 0.1)
				(type default)
			)
			(layer "F.Fab")
		)
		(fp_line
			(start 0.120396 0.3048)
			(end 0.120396 0.2794)
			(stroke
				(width 0.1)
				(type default)
			)
			(layer "F.Fab")
		)
		(fp_line
			(start 0.12065 -0.3048)
			(end 0.67945 -0.3048)
			(stroke
				(width 0.1)
				(type default)
			)
			(layer "F.Fab")
		)
		(fp_line
			(start 0.12065 -0.2794)
			(end 0.12065 -0.3048)
			(stroke
				(width 0.1)
				(type default)
			)
			(layer "F.Fab")
		)
		(fp_line
			(start 0.67945 -0.3048)
			(end 0.67945 0.3048)
			(stroke
				(width 0.1)
				(type default)
			)
			(layer "F.Fab")
		)
		(fp_line
			(start 0.67945 0.3048)
			(end 0.120396 0.3048)
			(stroke
				(width 0.1)
				(type default)
			)
			(layer "F.Fab")
		)
		(pad "1" smd circle
			(at -0.40005 0)
			(size 0 0)
			(layers "F.Cu" "F.Mask" "F.Paste")
			(net "P3V3_AUX")
		)
		(pad "2" smd circle
			(at 0.40005 0)
			(size 0 0)
			(layers "F.Cu" "F.Mask" "F.Paste")
			(net "JTAG_BMC_OE_N")
		)
	)
)
